(kicad_pcb
	(version 20260206)
	(generator "pcbnew")
	(generator_version "10.0")
	(general
		(thickness 1.6)
		(legacy_teardrops no)
	)
	(paper "A4")
	(title_block
		(title "01162023_DA0F0TEBIF0_F0T_Expander_BD_F_brd_V02_OCP.brd")
		(comment 1 "Grand Teton / footprints 1935-1941 of 9728")
	)
	(layers
		(0 "F.Cu" signal "TOP")
		(4 "In1.Cu" signal "GND")
		(6 "In2.Cu" signal "VCC")
		(8 "In3.Cu" signal "VCC1")
		(10 "In4.Cu" signal "GND1")
		(12 "In5.Cu" signal "IN1")
		(14 "In6.Cu" signal "GND2")
		(16 "In7.Cu" signal "IN2")
		(18 "In8.Cu" signal "GND3")
		(20 "In9.Cu" signal "IN3")
		(22 "In10.Cu" signal "GND4")
		(24 "In11.Cu" signal "IN4")
		(26 "In12.Cu" signal "GND5")
		(28 "In13.Cu" signal "IN5")
		(30 "In14.Cu" signal "GND6")
		(32 "In15.Cu" signal "IN6")
		(34 "In16.Cu" signal "GND7")
		(2 "B.Cu" signal "BOTTOM")
		(9 "F.Adhes" user "F.Adhesive")
		(11 "B.Adhes" user "B.Adhesive")
		(13 "F.Paste" user "Package Geometry/Pastemask Top")
		(15 "B.Paste" user "Package Geometry/Pastemask Bottom")
		(5 "F.SilkS" user "Ref Des/Silkscreen Top")
		(7 "B.SilkS" user "Ref Des/Silkscreen Bottom")
		(1 "F.Mask" user "Board Geometry/Soldermask Top")
		(3 "B.Mask" user "Board Geometry/Soldermask Bottom")
		(17 "Dwgs.User" user "User.Drawings")
		(19 "Cmts.User" user "User.Comments")
		(21 "Eco1.User" user "User.Eco1")
		(23 "Eco2.User" user "User.Eco2")
		(25 "Edge.Cuts" user "Board Geometry/Outline")
		(27 "Margin" user)
		(31 "F.CrtYd" user "Package Geometry/Place Bound Top")
		(29 "B.CrtYd" user "Package Geometry/Place Bound Bottom")
		(35 "F.Fab" user "Ref Des/Assembly Top")
		(33 "B.Fab" user "Ref Des/Assembly Bottom")
	)
	(footprint ""
		(layer "F.Cu")
		(at 457.586334 -366.913922)
		(property "Reference" "R6690"
			(at 0 0 0)
			(layer "F.SilkS")
			(hide yes)
			(effects
				(font
					(size 1.27 1.27)
				)
			)
		)
		(property "Value" ""
			(at 0 0 0)
			(layer "F.Fab")
			(effects
				(font
					(size 1.27 1.27)
				)
			)
		)
		(duplicate_pad_numbers_are_jumpers no)
		(fp_line
			(start -0.7874 -0.4064)
			(end 0.7874 -0.4064)
			(stroke
				(width 0.1524)
				(type default)
			)
			(layer "F.SilkS")
		)
		(fp_line
			(start -0.7874 0.4064)
			(end -0.7874 -0.4064)
			(stroke
				(width 0.1524)
				(type default)
			)
			(layer "F.SilkS")
		)
		(fp_line
			(start 0.7874 -0.4064)
			(end 0.7874 0.4064)
			(stroke
				(width 0.1524)
				(type default)
			)
			(layer "F.SilkS")
		)
		(fp_line
			(start 0.7874 0.4064)
			(end -0.7874 0.4064)
			(stroke
				(width 0.1524)
				(type default)
			)
			(layer "F.SilkS")
		)
		(fp_line
			(start -0.67945 -0.305054)
			(end -0.12065 -0.305054)
			(stroke
				(width 0.1)
				(type default)
			)
			(layer "F.Fab")
		)
		(fp_line
			(start -0.67945 0.3048)
			(end -0.67945 -0.305054)
			(stroke
				(width 0.1)
				(type default)
			)
			(layer "F.Fab")
		)
		(fp_line
			(start -0.12065 -0.305054)
			(end -0.12065 -0.2794)
			(stroke
				(width 0.1)
				(type default)
			)
			(layer "F.Fab")
		)
		(fp_line
			(start -0.12065 -0.2794)
			(end 0.12065 -0.2794)
			(stroke
				(width 0.1)
				(type default)
			)
			(layer "F.Fab")
		)
		(fp_line
			(start -0.12065 0.2794)
			(end -0.12065 0.3048)
			(stroke
				(width 0.1)
				(type default)
			)
			(layer "F.Fab")
		)
		(fp_line
			(start -0.12065 0.3048)
			(end -0.67945 0.3048)
			(stroke
				(width 0.1)
				(type default)
			)
			(layer "F.Fab")
		)
		(fp_line
			(start 0.120396 0.2794)
			(end -0.12065 0.2794)
			(stroke
				(width 0.1)
				(type default)
			)
			(layer "F.Fab")
		)
		(fp_line
			(start 0.120396 0.3048)
			(end 0.120396 0.2794)
			(stroke
				(width 0.1)
				(type default)
			)
			(layer "F.Fab")
		)
		(fp_line
			(start 0.12065 -0.3048)
			(end 0.67945 -0.3048)
			(stroke
				(width 0.1)
				(type default)
			)
			(layer "F.Fab")
		)
		(fp_line
			(start 0.12065 -0.2794)
			(end 0.12065 -0.3048)
			(stroke
				(width 0.1)
				(type default)
			)
			(layer "F.Fab")
		)
		(fp_line
			(start 0.67945 -0.3048)
			(end 0.67945 0.3048)
			(stroke
				(width 0.1)
				(type default)
			)
			(layer "F.Fab")
		)
		(fp_line
			(start 0.67945 0.3048)
			(end 0.120396 0.3048)
			(stroke
				(width 0.1)
				(type default)
			)
			(layer "F.Fab")
		)
		(pad "1" smd circle
			(at -0.40005 0)
			(size 0 0)
			(layers "F.Cu" "F.Mask" "F.Paste")
			(net "GPU_3V3IO_RSVD4_N")
		)
		(pad "2" smd circle
			(at 0.40005 0)
			(size 0 0)
			(layers "F.Cu" "F.Mask" "F.Paste")
			(net "P3V3_AUX")
		)
	)
	(footprint ""
		(layer "F.Cu")
		(at 235.196126 -254.18542 -90)
		(property "Reference" "C4338"
			(at 0 0 270)
			(layer "F.SilkS")
			(hide yes)
			(effects
				(font
					(size 1.27 1.27)
				)
			)
		)
		(property "Value" ""
			(at 0 0 270)
			(layer "F.Fab")
			(effects
				(font
					(size 1.27 1.27)
				)
			)
		)
		(duplicate_pad_numbers_are_jumpers no)
		(fp_line
			(start -1.2954 0.5842)
			(end -1.2954 -0.5842)
			(stroke
				(width 0.1524)
				(type default)
			)
			(layer "F.SilkS")
		)
		(fp_line
			(start 1.2954 0.5842)
			(end -1.2954 0.5842)
			(stroke
				(width 0.1524)
				(type default)
			)
			(layer "F.SilkS")
		)
		(fp_line
			(start -1.2954 -0.5842)
			(end 1.2954 -0.5842)
			(stroke
				(width 0.1524)
				(type default)
			)
			(layer "F.SilkS")
		)
		(fp_line
			(start 1.2954 -0.5842)
			(end 1.2954 0.5842)
			(stroke
				(width 0.1524)
				(type default)
			)
			(layer "F.SilkS")
		)
		(fp_line
			(start -0.8636 0.4572)
			(end -0.8636 0.4064)
			(stroke
				(width 0.1)
				(type default)
			)
			(layer "F.Fab")
		)
		(fp_line
			(start 0.8636 0.4572)
			(end -0.8636 0.4572)
			(stroke
				(width 0.1)
				(type default)
			)
			(layer "F.Fab")
		)
		(fp_line
			(start -1.1938 0.4064)
			(end -1.1938 -0.4064)
			(stroke
				(width 0.1)
				(type default)
			)
			(layer "F.Fab")
		)
		(fp_line
			(start -0.8636 0.4064)
			(end -1.1938 0.4064)
			(stroke
				(width 0.1)
				(type default)
			)
			(layer "F.Fab")
		)
		(fp_line
			(start 0.8636 0.4064)
			(end 0.8636 0.4572)
			(stroke
				(width 0.1)
				(type default)
			)
			(layer "F.Fab")
		)
		(fp_line
			(start 1.1938 0.4064)
			(end 0.8636 0.4064)
			(stroke
				(width 0.1)
				(type default)
			)
			(layer "F.Fab")
		)
		(fp_line
			(start -1.1938 -0.4064)
			(end -0.8636 -0.4064)
			(stroke
				(width 0.1)
				(type default)
			)
			(layer "F.Fab")
		)
		(fp_line
			(start -0.8636 -0.4064)
			(end -0.8636 -0.4572)
			(stroke
				(width 0.1)
				(type default)
			)
			(layer "F.Fab")
		)
		(fp_line
			(start 0.8636 -0.4064)
			(end 1.1938 -0.4064)
			(stroke
				(width 0.1)
				(type default)
			)
			(layer "F.Fab")
		)
		(fp_line
			(start 1.1938 -0.4064)
			(end 1.1938 0.4064)
			(stroke
				(width 0.1)
				(type default)
			)
			(layer "F.Fab")
		)
		(fp_line
			(start -0.8636 -0.4572)
			(end 0.8636 -0.4572)
			(stroke
				(width 0.1)
				(type default)
			)
			(layer "F.Fab")
		)
		(fp_line
			(start 0.8636 -0.4572)
			(end 0.8636 -0.4064)
			(stroke
				(width 0.1)
				(type default)
			)
			(layer "F.Fab")
		)
		(pad "1" smd rect
			(at -0.7366 0 180)
			(size 0.7112 0.8128)
			(layers "F.Cu" "F.Mask" "F.Paste")
			(net "P1V25_SERDES_VDDPLL_PEX2_C0")
		)
		(pad "2" smd rect
			(at 0.7366 0 180)
			(size 0.7112 0.8128)
			(layers "F.Cu" "F.Mask" "F.Paste")
			(net "GND")
		)
	)
	(footprint ""
		(layer "F.Cu")
		(at 371.924834 -259.378958)
		(property "Reference" "R1464"
			(at 0 0 0)
			(layer "F.SilkS")
			(hide yes)
			(effects
				(font
					(size 1.27 1.27)
				)
			)
		)
		(property "Value" ""
			(at 0 0 0)
			(layer "F.Fab")
			(effects
				(font
					(size 1.27 1.27)
				)
			)
		)
		(duplicate_pad_numbers_are_jumpers no)
		(fp_line
			(start -0.7874 -0.4064)
			(end 0.7874 -0.4064)
			(stroke
				(width 0.1524)
				(type default)
			)
			(layer "F.SilkS")
		)
		(fp_line
			(start -0.7874 0.4064)
			(end -0.7874 -0.4064)
			(stroke
				(width 0.1524)
				(type default)
			)
			(layer "F.SilkS")
		)
		(fp_line
			(start 0.7874 -0.4064)
			(end 0.7874 0.4064)
			(stroke
				(width 0.1524)
				(type default)
			)
			(layer "F.SilkS")
		)
		(fp_line
			(start 0.7874 0.4064)
			(end -0.7874 0.4064)
			(stroke
				(width 0.1524)
				(type default)
			)
			(layer "F.SilkS")
		)
		(fp_line
			(start -0.67945 -0.305054)
			(end -0.12065 -0.305054)
			(stroke
				(width 0.1)
				(type default)
			)
			(layer "F.Fab")
		)
		(fp_line
			(start -0.67945 0.3048)
			(end -0.67945 -0.305054)
			(stroke
				(width 0.1)
				(type default)
			)
			(layer "F.Fab")
		)
		(fp_line
			(start -0.12065 -0.305054)
			(end -0.12065 -0.2794)
			(stroke
				(width 0.1)
				(type default)
			)
			(layer "F.Fab")
		)
		(fp_line
			(start -0.12065 -0.2794)
			(end 0.12065 -0.2794)
			(stroke
				(width 0.1)
				(type default)
			)
			(layer "F.Fab")
		)
		(fp_line
			(start -0.12065 0.2794)
			(end -0.12065 0.3048)
			(stroke
				(width 0.1)
				(type default)
			)
			(layer "F.Fab")
		)
		(fp_line
			(start -0.12065 0.3048)
			(end -0.67945 0.3048)
			(stroke
				(width 0.1)
				(type default)
			)
			(layer "F.Fab")
		)
		(fp_line
			(start 0.120396 0.2794)
			(end -0.12065 0.2794)
			(stroke
				(width 0.1)
				(type default)
			)
			(layer "F.Fab")
		)
		(fp_line
			(start 0.120396 0.3048)
			(end 0.120396 0.2794)
			(stroke
				(width 0.1)
				(type default)
			)
			(layer "F.Fab")
		)
		(fp_line
			(start 0.12065 -0.3048)
			(end 0.67945 -0.3048)
			(stroke
				(width 0.1)
				(type default)
			)
			(layer "F.Fab")
		)
		(fp_line
			(start 0.12065 -0.2794)
			(end 0.12065 -0.3048)
			(stroke
				(width 0.1)
				(type default)
			)
			(layer "F.Fab")
		)
		(fp_line
			(start 0.67945 -0.3048)
			(end 0.67945 0.3048)
			(stroke
				(width 0.1)
				(type default)
			)
			(layer "F.Fab")
		)
		(fp_line
			(start 0.67945 0.3048)
			(end 0.120396 0.3048)
			(stroke
				(width 0.1)
				(type default)
			)
			(layer "F.Fab")
		)
		(pad "1" smd circle
			(at -0.40005 0)
			(size 0 0)
			(layers "F.Cu" "F.Mask" "F.Paste")
			(net "PEX3_SYS_ERR_N_G")
		)
		(pad "2" smd circle
			(at 0.40005 0)
			(size 0 0)
			(layers "F.Cu" "F.Mask" "F.Paste")
			(net "P3V3_AUX")
		)
	)
	(footprint ""
		(layer "F.Cu")
		(at 126.816612 -162.003994 90)
		(property "Reference" "PC632"
			(at 0 0 90)
			(layer "F.SilkS")
			(hide yes)
			(effects
				(font
					(size 1.27 1.27)
				)
			)
		)
		(property "Value" ""
			(at 0 0 90)
			(layer "F.Fab")
			(effects
				(font
					(size 1.27 1.27)
				)
			)
		)
		(duplicate_pad_numbers_are_jumpers no)
		(fp_line
			(start 0.7874 -0.4064)
			(end 0.7874 0.4064)
			(stroke
				(width 0.1524)
				(type default)
			)
			(layer "F.SilkS")
		)
		(fp_line
			(start -0.7874 -0.4064)
			(end 0.7874 -0.4064)
			(stroke
				(width 0.1524)
				(type default)
			)
			(layer "F.SilkS")
		)
		(fp_line
			(start 0.7874 0.4064)
			(end -0.7874 0.4064)
			(stroke
				(width 0.1524)
				(type default)
			)
			(layer "F.SilkS")
		)
		(fp_line
			(start -0.7874 0.4064)
			(end -0.7874 -0.4064)
			(stroke
				(width 0.1524)
				(type default)
			)
			(layer "F.SilkS")
		)
		(fp_line
			(start -0.12065 -0.305054)
			(end -0.12065 -0.2794)
			(stroke
				(width 0.1)
				(type default)
			)
			(layer "F.Fab")
		)
		(fp_line
			(start -0.67945 -0.305054)
			(end -0.12065 -0.305054)
			(stroke
				(width 0.1)
				(type default)
			)
			(layer "F.Fab")
		)
		(fp_line
			(start 0.67945 -0.3048)
			(end 0.67945 0.3048)
			(stroke
				(width 0.1)
				(type default)
			)
			(layer "F.Fab")
		)
		(fp_line
			(start 0.12065 -0.3048)
			(end 0.67945 -0.3048)
			(stroke
				(width 0.1)
				(type default)
			)
			(layer "F.Fab")
		)
		(fp_line
			(start 0.12065 -0.2794)
			(end 0.12065 -0.3048)
			(stroke
				(width 0.1)
				(type default)
			)
			(layer "F.Fab")
		)
		(fp_line
			(start -0.12065 -0.2794)
			(end 0.12065 -0.2794)
			(stroke
				(width 0.1)
				(type default)
			)
			(layer "F.Fab")
		)
		(fp_line
			(start 0.120396 0.2794)
			(end -0.12065 0.2794)
			(stroke
				(width 0.1)
				(type default)
			)
			(layer "F.Fab")
		)
		(fp_line
			(start -0.12065 0.2794)
			(end -0.12065 0.3048)
			(stroke
				(width 0.1)
				(type default)
			)
			(layer "F.Fab")
		)
		(fp_line
			(start 0.67945 0.3048)
			(end 0.120396 0.3048)
			(stroke
				(width 0.1)
				(type default)
			)
			(layer "F.Fab")
		)
		(fp_line
			(start 0.120396 0.3048)
			(end 0.120396 0.2794)
			(stroke
				(width 0.1)
				(type default)
			)
			(layer "F.Fab")
		)
		(fp_line
			(start -0.12065 0.3048)
			(end -0.67945 0.3048)
			(stroke
				(width 0.1)
				(type default)
			)
			(layer "F.Fab")
		)
		(fp_line
			(start -0.67945 0.3048)
			(end -0.67945 -0.305054)
			(stroke
				(width 0.1)
				(type default)
			)
			(layer "F.Fab")
		)
		(pad "1" smd circle
			(at -0.40005 0 90)
			(size 0 0)
			(layers "F.Cu" "F.Mask" "F.Paste")
			(net "P12V_NIC2_CO_SS")
		)
		(pad "2" smd circle
			(at 0.40005 0 90)
			(size 0 0)
			(layers "F.Cu" "F.Mask" "F.Paste")
			(net "GND")
		)
	)
	(footprint ""
		(layer "F.Cu")
		(at 357.367586 -263.57072)
		(property "Reference" "PJ7"
			(at 0 0 0)
			(layer "F.SilkS")
			(hide yes)
			(effects
				(font
					(size 1.27 1.27)
				)
			)
		)
		(property "Value" ""
			(at 0 0 0)
			(layer "F.Fab")
			(effects
				(font
					(size 1.27 1.27)
				)
			)
		)
		(duplicate_pad_numbers_are_jumpers no)
		(pad "1" smd circle
			(at -0.7493 0 90)
			(size 0 0)
			(layers "F.Cu" "F.Mask" "F.Paste")
			(net "SH_P0V8_PEX2_VSEN2_L")
		)
		(pad "2" smd rect
			(at 0.7493 0 270)
			(size 0.7112 0.8128)
			(layers "F.Cu" "F.Mask" "F.Paste")
			(net "SH_P0V8_PEX2_VSEN2_R")
		)
		(zone
			(layer "F.Cu")
			(hatch none 0.5)
			(connect_pads
				(clearance 0)
			)
			(min_thickness 0.25)
			(keepout
				(tracks allowed)
				(vias not_allowed)
				(pads allowed)
				(copperpour not_allowed)
				(footprints allowed)
			)
			(placement
				(enabled no)
				(sheetname "")
			)
			(fill
				(thermal_gap 0.5)
				(thermal_bridge_width 0.5)
				(island_removal_mode 0)
			)
			(polygon
				(pts
					(xy 356.186486 -263.159494) (xy 358.574086 -263.159494) (xy 358.574086 -263.97712) (xy 356.186486 -263.97712)
				)
			)
		)
	)
	(footprint ""
		(layer "F.Cu")
		(at 277.089616 -405.074374 -90)
		(property "Reference" "R1811"
			(at 0 0 270)
			(layer "F.SilkS")
			(hide yes)
			(effects
				(font
					(size 1.27 1.27)
				)
			)
		)
		(property "Value" ""
			(at 0 0 270)
			(layer "F.Fab")
			(effects
				(font
					(size 1.27 1.27)
				)
			)
		)
		(duplicate_pad_numbers_are_jumpers no)
		(fp_line
			(start -0.7874 0.4064)
			(end -0.7874 -0.4064)
			(stroke
				(width 0.1524)
				(type default)
			)
			(layer "F.SilkS")
		)
		(fp_line
			(start 0.7874 0.4064)
			(end -0.7874 0.4064)
			(stroke
				(width 0.1524)
				(type default)
			)
			(layer "F.SilkS")
		)
		(fp_line
			(start -0.7874 -0.4064)
			(end 0.7874 -0.4064)
			(stroke
				(width 0.1524)
				(type default)
			)
			(layer "F.SilkS")
		)
		(fp_line
			(start 0.7874 -0.4064)
			(end 0.7874 0.4064)
			(stroke
				(width 0.1524)
				(type default)
			)
			(layer "F.SilkS")
		)
		(fp_line
			(start -0.67945 0.3048)
			(end -0.67945 -0.305054)
			(stroke
				(width 0.1)
				(type default)
			)
			(layer "F.Fab")
		)
		(fp_line
			(start -0.12065 0.3048)
			(end -0.67945 0.3048)
			(stroke
				(width 0.1)
				(type default)
			)
			(layer "F.Fab")
		)
		(fp_line
			(start 0.120396 0.3048)
			(end 0.120396 0.2794)
			(stroke
				(width 0.1)
				(type default)
			)
			(layer "F.Fab")
		)
		(fp_line
			(start 0.67945 0.3048)
			(end 0.120396 0.3048)
			(stroke
				(width 0.1)
				(type default)
			)
			(layer "F.Fab")
		)
		(fp_line
			(start -0.12065 0.2794)
			(end -0.12065 0.3048)
			(stroke
				(width 0.1)
				(type default)
			)
			(layer "F.Fab")
		)
		(fp_line
			(start 0.120396 0.2794)
			(end -0.12065 0.2794)
			(stroke
				(width 0.1)
				(type default)
			)
			(layer "F.Fab")
		)
		(fp_line
			(start -0.12065 -0.2794)
			(end 0.12065 -0.2794)
			(stroke
				(width 0.1)
				(type default)
			)
			(layer "F.Fab")
		)
		(fp_line
			(start 0.12065 -0.2794)
			(end 0.12065 -0.3048)
			(stroke
				(width 0.1)
				(type default)
			)
			(layer "F.Fab")
		)
		(fp_line
			(start 0.12065 -0.3048)
			(end 0.67945 -0.3048)
			(stroke
				(width 0.1)
				(type default)
			)
			(layer "F.Fab")
		)
		(fp_line
			(start 0.67945 -0.3048)
			(end 0.67945 0.3048)
			(stroke
				(width 0.1)
				(type default)
			)
			(layer "F.Fab")
		)
		(fp_line
			(start -0.67945 -0.305054)
			(end -0.12065 -0.305054)
			(stroke
				(width 0.1)
				(type default)
			)
			(layer "F.Fab")
		)
		(fp_line
			(start -0.12065 -0.305054)
			(end -0.12065 -0.2794)
			(stroke
				(width 0.1)
				(type default)
			)
			(layer "F.Fab")
		)
		(pad "1" smd circle
			(at -0.40005 0 270)
			(size 0 0)
			(layers "F.Cu" "F.Mask" "F.Paste")
			(net "P3V3_AUX")
		)
		(pad "2" smd circle
			(at 0.40005 0 270)
			(size 0 0)
			(layers "F.Cu" "F.Mask" "F.Paste")
			(net "BIC_SYS_READY_R_N")
		)
	)
	(footprint ""
		(layer "F.Cu")
		(at 224.851976 -365.978186 180)
		(property "Reference" "PR41"
			(at 0 0 180)
			(layer "F.SilkS")
			(hide yes)
			(effects
				(font
					(size 1.27 1.27)
				)
			)
		)
		(property "Value" ""
			(at 0 0 180)
			(layer "F.Fab")
			(effects
				(font
					(size 1.27 1.27)
				)
			)
		)
		(duplicate_pad_numbers_are_jumpers no)
		(fp_line
			(start 0.7874 0.4064)
			(end -0.7874 0.4064)
			(stroke
				(width 0.1524)
				(type default)
			)
			(layer "F.SilkS")
		)
		(fp_line
			(start 0.7874 -0.4064)
			(end 0.7874 0.4064)
			(stroke
				(width 0.1524)
				(type default)
			)
			(layer "F.SilkS")
		)
		(fp_line
			(start -0.7874 0.4064)
			(end -0.7874 -0.4064)
			(stroke
				(width 0.1524)
				(type default)
			)
			(layer "F.SilkS")
		)
		(fp_line
			(start -0.7874 -0.4064)
			(end 0.7874 -0.4064)
			(stroke
				(width 0.1524)
				(type default)
			)
			(layer "F.SilkS")
		)
		(fp_line
			(start 0.67945 0.3048)
			(end 0.120396 0.3048)
			(stroke
				(width 0.1)
				(type default)
			)
			(layer "F.Fab")
		)
		(fp_line
			(start 0.67945 -0.3048)
			(end 0.67945 0.3048)
			(stroke
				(width 0.1)
				(type default)
			)
			(layer "F.Fab")
		)
		(fp_line
			(start 0.12065 -0.2794)
			(end 0.12065 -0.3048)
			(stroke
				(width 0.1)
				(type default)
			)
			(layer "F.Fab")
		)
		(fp_line
			(start 0.12065 -0.3048)
			(end 0.67945 -0.3048)
			(stroke
				(width 0.1)
				(type default)
			)
			(layer "F.Fab")
		)
		(fp_line
			(start 0.120396 0.3048)
			(end 0.120396 0.2794)
			(stroke
				(width 0.1)
				(type default)
			)
			(layer "F.Fab")
		)
		(fp_line
			(start 0.120396 0.2794)
			(end -0.12065 0.2794)
			(stroke
				(width 0.1)
				(type default)
			)
			(layer "F.Fab")
		)
		(fp_line
			(start -0.12065 0.3048)
			(end -0.67945 0.3048)
			(stroke
				(width 0.1)
				(type default)
			)
			(layer "F.Fab")
		)
		(fp_line
			(start -0.12065 0.2794)
			(end -0.12065 0.3048)
			(stroke
				(width 0.1)
				(type default)
			)
			(layer "F.Fab")
		)
		(fp_line
			(start -0.12065 -0.2794)
			(end 0.12065 -0.2794)
			(stroke
				(width 0.1)
				(type default)
			)
			(layer "F.Fab")
		)
		(fp_line
			(start -0.12065 -0.305054)
			(end -0.12065 -0.2794)
			(stroke
				(width 0.1)
				(type default)
			)
			(layer "F.Fab")
		)
		(fp_line
			(start -0.67945 0.3048)
			(end -0.67945 -0.305054)
			(stroke
				(width 0.1)
				(type default)
			)
			(layer "F.Fab")
		)
		(fp_line
			(start -0.67945 -0.305054)
			(end -0.12065 -0.305054)
			(stroke
				(width 0.1)
				(type default)
			)
			(layer "F.Fab")
		)
		(pad "1" smd circle
			(at -0.40005 0 180)
			(size 0 0)
			(layers "F.Cu" "F.Mask" "F.Paste")
			(net "HSC_OCREF")
		)
		(pad "2" smd circle
			(at 0.40005 0 180)
			(size 0 0)
			(layers "F.Cu" "F.Mask" "F.Paste")
			(net "AGND_HSC")
		)
	)
)
